# BASEBOARD_FAB2 (Tioga Pass) — schematic netlist excerpt (pin names and nets, part order shuffled) for the footprints in the layout excerpt that follows; sources: Cadence DE-HDL packaged netlist, KiCad conversion of Wiwynn_Tioga_Pass_MB.brd

R2M2  RES  4.75K 1% CHIP  pkg 0402  page 157 : A = P3V3_STBY ; B = FM_ADR_SMI_GPIO_N
C7E6  CAP  10UF 16V 10% X6S  pkg 0805  page 198 : A = P12V_STBY ; B = GND
R7E12  RES  1.00K 1% CHIP  pkg 0402  page 241 : A = P5V_STBY ; B = PWRGD_P5V_STBY_R

(kicad_pcb
	(version 20260206)
	(generator "pcbnew")
	(generator_version "10.0")
	(general
		(thickness 1.6)
		(legacy_teardrops no)
	)
	(paper "A4")
	(title_block
		(title "Wiwynn_Tioga_Pass_MB.brd")
		(comment 1 "Tioga Pass / footprints 170-172 of 4770")
	)
	(layers
		(0 "F.Cu" signal "TOP")
		(4 "In1.Cu" signal "L2GND")
		(6 "In2.Cu" signal "L3")
		(8 "In3.Cu" signal "L4GND")
		(10 "In4.Cu" signal "L5")
		(12 "In5.Cu" signal "L6GND")
		(14 "In6.Cu" signal "L7VCC")
		(16 "In7.Cu" signal "L8VCC")
		(18 "In8.Cu" signal "L9GND")
		(20 "In9.Cu" signal "L10")
		(22 "In10.Cu" signal "L11GND")
		(24 "In11.Cu" signal "L12")
		(26 "In12.Cu" signal "L13GND")
		(2 "B.Cu" signal "BOTTOM")
		(9 "F.Adhes" user "F.Adhesive")
		(11 "B.Adhes" user "B.Adhesive")
		(13 "F.Paste" user "Package Geometry/Pastemask Top")
		(15 "B.Paste" user "Package Geometry/Pastemask Bottom")
		(5 "F.SilkS" user "Ref Des/Silkscreen Top")
		(7 "B.SilkS" user "Ref Des/Silkscreen Bottom")
		(1 "F.Mask" user "Board Geometry/Soldermask Top")
		(3 "B.Mask" user "Board Geometry/Soldermask Bottom")
		(17 "Dwgs.User" user "User.Drawings")
		(19 "Cmts.User" user "User.Comments")
		(21 "Eco1.User" user "User.Eco1")
		(23 "Eco2.User" user "User.Eco2")
		(25 "Edge.Cuts" user "Board Geometry/Outline")
		(27 "Margin" user)
		(31 "F.CrtYd" user "Package Geometry/Place Bound Top")
		(29 "B.CrtYd" user "Package Geometry/Place Bound Bottom")
		(35 "F.Fab" user "Ref Des/Assembly Top")
		(33 "B.Fab" user "Ref Des/Assembly Bottom")
	)
	(footprint ""
		(layer "F.Cu")
		(at 414.8328 -113.2332 90)
		(property "Reference" "R2M2"
			(at 0 0 90)
			(layer "F.SilkS")
			(hide yes)
			(effects
				(font
					(size 1.27 1.27)
				)
			)
		)
		(property "Value" ""
			(at 0 0 90)
			(layer "F.Fab")
			(effects
				(font
					(size 1.27 1.27)
				)
			)
		)
		(duplicate_pad_numbers_are_jumpers no)
		(fp_poly
			(pts
				(xy -0.2794 -0.1016) (xy 0.2794 -0.1016) (xy 0.2794 0.9906) (xy -0.2794 0.9906)
			)
			(stroke
				(width 0)
				(type default)
			)
			(fill no)
			(layer "F.CrtYd")
		)
		(fp_line
			(start 0.2794 -0.1016)
			(end -0.2794 -0.1016)
			(stroke
				(width 0.1)
				(type default)
			)
			(layer "F.Fab")
		)
		(fp_line
			(start -0.2794 -0.1016)
			(end -0.2794 0.9906)
			(stroke
				(width 0.1)
				(type default)
			)
			(layer "F.Fab")
		)
		(fp_line
			(start 0.2794 0.9906)
			(end 0.2794 -0.1016)
			(stroke
				(width 0.1)
				(type default)
			)
			(layer "F.Fab")
		)
		(fp_line
			(start -0.2794 0.9906)
			(end 0.2794 0.9906)
			(stroke
				(width 0.1)
				(type default)
			)
			(layer "F.Fab")
		)
		(pad "1" smd rect
			(at 0 0 90)
			(size 0.508 0.508)
			(layers "F.Cu" "F.Mask" "F.Paste")
			(net "P3V3_STBY")
		)
		(pad "2" smd rect
			(at 0 0.889 90)
			(size 0.508 0.508)
			(layers "F.Cu" "F.Mask" "F.Paste")
			(net "FM_ADR_SMI_GPIO_N")
		)
		(zone
			(layer "F.Cu")
			(hatch none 0.5)
			(connect_pads
				(clearance 0)
			)
			(min_thickness 0.25)
			(keepout
				(tracks allowed)
				(vias not_allowed)
				(pads allowed)
				(copperpour not_allowed)
				(footprints allowed)
			)
			(placement
				(enabled no)
				(sheetname "")
			)
			(fill
				(thermal_gap 0.5)
				(thermal_bridge_width 0.5)
				(island_removal_mode 0)
			)
			(polygon
				(pts
					(xy 415.0868 -112.9792) (xy 415.0868 -113.4872) (xy 415.4678 -113.4872) (xy 415.4678 -112.9792)
				)
			)
		)
		(zone
			(layer "F.Cu")
			(hatch none 0.5)
			(connect_pads
				(clearance 0)
			)
			(min_thickness 0.25)
			(keepout
				(tracks not_allowed)
				(vias allowed)
				(pads allowed)
				(copperpour not_allowed)
				(footprints allowed)
			)
			(placement
				(enabled no)
				(sheetname "")
			)
			(fill
				(thermal_gap 0.5)
				(thermal_bridge_width 0.5)
				(island_removal_mode 0)
			)
			(polygon
				(pts
					(xy 415.4678 -112.9792) (xy 415.4678 -113.4872) (xy 415.0868 -113.4872) (xy 415.0868 -112.9792)
				)
			)
		)
	)
	(footprint ""
		(layer "F.Cu")
		(at 391.414 -71.9455)
		(property "Reference" "R7E12"
			(at 0 0 0)
			(layer "F.SilkS")
			(hide yes)
			(effects
				(font
					(size 1.27 1.27)
				)
			)
		)
		(property "Value" ""
			(at 0 0 0)
			(layer "F.Fab")
			(effects
				(font
					(size 1.27 1.27)
				)
			)
		)
		(duplicate_pad_numbers_are_jumpers no)
		(fp_poly
			(pts
				(xy -0.2794 -0.1016) (xy 0.2794 -0.1016) (xy 0.2794 0.9906) (xy -0.2794 0.9906)
			)
			(stroke
				(width 0)
				(type default)
			)
			(fill no)
			(layer "F.CrtYd")
		)
		(fp_line
			(start -0.2794 -0.1016)
			(end -0.2794 0.9906)
			(stroke
				(width 0.1)
				(type default)
			)
			(layer "F.Fab")
		)
		(fp_line
			(start -0.2794 0.9906)
			(end 0.2794 0.9906)
			(stroke
				(width 0.1)
				(type default)
			)
			(layer "F.Fab")
		)
		(fp_line
			(start 0.2794 -0.1016)
			(end -0.2794 -0.1016)
			(stroke
				(width 0.1)
				(type default)
			)
			(layer "F.Fab")
		)
		(fp_line
			(start 0.2794 0.9906)
			(end 0.2794 -0.1016)
			(stroke
				(width 0.1)
				(type default)
			)
			(layer "F.Fab")
		)
		(pad "1" smd rect
			(at 0 0)
			(size 0.508 0.508)
			(layers "F.Cu" "F.Mask" "F.Paste")
			(net "P5V_STBY")
		)
		(pad "2" smd rect
			(at 0 0.889)
			(size 0.508 0.508)
			(layers "F.Cu" "F.Mask" "F.Paste")
			(net "PWRGD_P5V_STBY_R")
		)
		(zone
			(layer "F.Cu")
			(hatch none 0.5)
			(connect_pads
				(clearance 0)
			)
			(min_thickness 0.25)
			(keepout
				(tracks allowed)
				(vias not_allowed)
				(pads allowed)
				(copperpour not_allowed)
				(footprints allowed)
			)
			(placement
				(enabled no)
				(sheetname "")
			)
			(fill
				(thermal_gap 0.5)
				(thermal_bridge_width 0.5)
				(island_removal_mode 0)
			)
			(polygon
				(pts
					(xy 391.16 -71.6915) (xy 391.668 -71.6915) (xy 391.668 -71.3105) (xy 391.16 -71.3105)
				)
			)
		)
		(zone
			(layer "F.Cu")
			(hatch none 0.5)
			(connect_pads
				(clearance 0)
			)
			(min_thickness 0.25)
			(keepout
				(tracks not_allowed)
				(vias allowed)
				(pads allowed)
				(copperpour not_allowed)
				(footprints allowed)
			)
			(placement
				(enabled no)
				(sheetname "")
			)
			(fill
				(thermal_gap 0.5)
				(thermal_bridge_width 0.5)
				(island_removal_mode 0)
			)
			(polygon
				(pts
					(xy 391.16 -71.3105) (xy 391.668 -71.3105) (xy 391.668 -71.6915) (xy 391.16 -71.6915)
				)
			)
		)
	)
	(footprint ""
		(layer "F.Cu")
		(at 496.686332 -22.354794 90)
		(property "Reference" "C7E6"
			(at 0 0 90)
			(layer "F.SilkS")
			(hide yes)
			(effects
				(font
					(size 1.27 1.27)
				)
			)
		)
		(property "Value" ""
			(at 0 0 90)
			(layer "F.Fab")
			(effects
				(font
					(size 1.27 1.27)
				)
			)
		)
		(duplicate_pad_numbers_are_jumpers no)
		(fp_rect
			(start -0.7239 1.9939)
			(end 0.7239 -0.2159)
			(stroke
				(width 0)
				(type default)
			)
			(fill no)
			(layer "F.CrtYd")
		)
		(fp_line
			(start 0.7239 -0.2159)
			(end -0.7239 -0.2159)
			(stroke
				(width 0.1)
				(type default)
			)
			(layer "F.Fab")
		)
		(fp_line
			(start -0.7239 -0.2159)
			(end -0.7239 1.9939)
			(stroke
				(width 0.1)
				(type default)
			)
			(layer "F.Fab")
		)
		(fp_line
			(start 0.7239 1.9939)
			(end 0.7239 -0.2159)
			(stroke
				(width 0.1)
				(type default)
			)
			(layer "F.Fab")
		)
		(fp_line
			(start -0.7239 1.9939)
			(end 0.7239 1.9939)
			(stroke
				(width 0.1)
				(type default)
			)
			(layer "F.Fab")
		)
		(pad "1" smd rect
			(at 0 0 90)
			(size 1.27 1.016)
			(layers "F.Cu" "F.Mask" "F.Paste")
			(net "P12V_STBY")
		)
		(pad "2" smd rect
			(at 0 1.778 90)
			(size 1.27 1.016)
			(layers "F.Cu" "F.Mask" "F.Paste")
			(net "GND")
		)
		(zone
			(layer "F.Cu")
			(hatch none 0.5)
			(connect_pads
				(clearance 0)
			)
			(min_thickness 0.25)
			(keepout
				(tracks not_allowed)
				(vias allowed)
				(pads allowed)
				(copperpour not_allowed)
				(footprints allowed)
			)
			(placement
				(enabled no)
				(sheetname "")
			)
			(fill
				(thermal_gap 0.5)
				(thermal_bridge_width 0.5)
				(island_removal_mode 0)
			)
			(polygon
				(pts
					(xy 497.956332 -21.719794) (xy 497.956332 -22.989794) (xy 497.194332 -22.989794) (xy 497.194332 -21.719794)
				)
			)
		)
	)
)
